1 2 3 4 5 6 7 8
1 2 3 4 5 6 7 8
D
C
B
A A
B
C
D
DRAWING NO.
SCALE DWG
DO NOT 
MODEL NAME
Wiwynn CorporationAPPD
CKD
DSN
DRN
SHEET
SIGNREV DESCRIPTION DATEMATERIAL
FINISH
OF
DIM IN  mm
59.10
0.00
(PTH)5.60
6.70
0.00
6.70
0.00
90.00
26.50
20.00
0.30
10.60
48.50
2-1.30
(NPTH)1.35
(NPTH)1.35
0.30
(NO TRACE AT ALL LAYERS)9.20
(PAD)(NO TRACE AT ALL LAYERS)9.20
7.89
0.00
51.22
59.10
29.55
3.00
19.40
39.70
61.10
Jess Wang 
Lenny Kao
Lenny Kao CD  
BryceCanyon
Jess Wang 2/9
2017
2/9
2017
BryceCanyon Front Panel Board 4L
IT150G / NPG150N T=1.6mm 
 1 1 
2/9
2017
2/9
2017
16369-SC VERSION B 2017-02-17
16369-SC VERSION A 2017-02-09
COMPONENT SIDE
SOLDER SIDE
SMT THUMB SCREW (086.2AT24.04R6)